# T6G (Grand Teton) — schematic netlist excerpt (pin names and nets, part order shuffled) for the footprints in the layout excerpt that follows; sources: Cadence DE-HDL packaged netlist, KiCad conversion of 04192023_DAF0TMB3IC0_F0TG_MB_C_brd_V02_OCP.brd

C2288  Q_CAP  22UF 4V 20% X6S  pkg C0402  page 72 : A = PVDDCR_SOC_P1 ; B = GND
R11667  Q_RES  33.2 1% CHIP  pkg 0402LF  page 81 : A = FM_SMB_2_ALERT_GPU_ISO_R_N ; B = FM_SMB_2_ALERT_GPU_ISO_N

(kicad_pcb
	(version 20260206)
	(generator "pcbnew")
	(generator_version "10.0")
	(general
		(thickness 1.6)
		(legacy_teardrops no)
	)
	(paper "A4")
	(title_block
		(title "04192023_DAF0TMB3IC0_F0TG_MB_C_brd_V02_OCP.brd")
		(comment 1 "Grand Teton / footprints 3352-3353 of 8354")
	)
	(layers
		(0 "F.Cu" signal "TOP")
		(4 "In1.Cu" signal "GND")
		(6 "In2.Cu" signal "IN1")
		(8 "In3.Cu" signal "GND1")
		(10 "In4.Cu" signal "IN2")
		(12 "In5.Cu" signal "GND2")
		(14 "In6.Cu" signal "IN3")
		(16 "In7.Cu" signal "GND3")
		(18 "In8.Cu" signal "VCC")
		(20 "In9.Cu" signal "VCC1")
		(22 "In10.Cu" signal "GND4")
		(24 "In11.Cu" signal "IN4")
		(26 "In12.Cu" signal "GND5")
		(28 "In13.Cu" signal "IN5")
		(30 "In14.Cu" signal "GND6")
		(32 "In15.Cu" signal "IN6")
		(34 "In16.Cu" signal "GND7")
		(2 "B.Cu" signal "BOTTOM")
		(9 "F.Adhes" user "F.Adhesive")
		(11 "B.Adhes" user "B.Adhesive")
		(13 "F.Paste" user "Package Geometry/Pastemask Top")
		(15 "B.Paste" user "Package Geometry/Pastemask Bottom")
		(5 "F.SilkS" user "Ref Des/Silkscreen Top")
		(7 "B.SilkS" user "Ref Des/Silkscreen Bottom")
		(1 "F.Mask" user "Board Geometry/Soldermask Top")
		(3 "B.Mask" user "Board Geometry/Soldermask Bottom")
		(17 "Dwgs.User" user "User.Drawings")
		(19 "Cmts.User" user "User.Comments")
		(21 "Eco1.User" user "User.Eco1")
		(23 "Eco2.User" user "User.Eco2")
		(25 "Edge.Cuts" user "Board Geometry/Outline")
		(27 "Margin" user)
		(31 "F.CrtYd" user "Package Geometry/Place Bound Top")
		(29 "B.CrtYd" user "Package Geometry/Place Bound Bottom")
		(35 "F.Fab" user "Ref Des/Assembly Top")
		(33 "B.Fab" user "Ref Des/Assembly Bottom")
	)
	(footprint ""
		(layer "F.Cu")
		(at 197.269608 -123.785376)
		(property "Reference" "R11667"
			(at 0 0 0)
			(layer "F.SilkS")
			(hide yes)
			(effects
				(font
					(size 1.27 1.27)
				)
			)
		)
		(property "Value" ""
			(at 0 0 0)
			(layer "F.Fab")
			(effects
				(font
					(size 1.27 1.27)
				)
			)
		)
		(duplicate_pad_numbers_are_jumpers no)
		(fp_line
			(start -0.7874 -0.4064)
			(end 0.7874 -0.4064)
			(stroke
				(width 0.1524)
				(type default)
			)
			(layer "F.SilkS")
		)
		(fp_line
			(start -0.7874 0.4064)
			(end -0.7874 -0.4064)
			(stroke
				(width 0.1524)
				(type default)
			)
			(layer "F.SilkS")
		)
		(fp_line
			(start 0.7874 -0.4064)
			(end 0.7874 0.4064)
			(stroke
				(width 0.1524)
				(type default)
			)
			(layer "F.SilkS")
		)
		(fp_line
			(start 0.7874 0.4064)
			(end -0.7874 0.4064)
			(stroke
				(width 0.1524)
				(type default)
			)
			(layer "F.SilkS")
		)
		(fp_line
			(start -0.67945 -0.305054)
			(end -0.12065 -0.305054)
			(stroke
				(width 0.1)
				(type default)
			)
			(layer "F.Fab")
		)
		(fp_line
			(start -0.67945 0.3048)
			(end -0.67945 -0.305054)
			(stroke
				(width 0.1)
				(type default)
			)
			(layer "F.Fab")
		)
		(fp_line
			(start -0.12065 -0.305054)
			(end -0.12065 -0.2794)
			(stroke
				(width 0.1)
				(type default)
			)
			(layer "F.Fab")
		)
		(fp_line
			(start -0.12065 -0.2794)
			(end 0.12065 -0.2794)
			(stroke
				(width 0.1)
				(type default)
			)
			(layer "F.Fab")
		)
		(fp_line
			(start -0.12065 0.2794)
			(end -0.12065 0.3048)
			(stroke
				(width 0.1)
				(type default)
			)
			(layer "F.Fab")
		)
		(fp_line
			(start -0.12065 0.3048)
			(end -0.67945 0.3048)
			(stroke
				(width 0.1)
				(type default)
			)
			(layer "F.Fab")
		)
		(fp_line
			(start 0.120396 0.2794)
			(end -0.12065 0.2794)
			(stroke
				(width 0.1)
				(type default)
			)
			(layer "F.Fab")
		)
		(fp_line
			(start 0.120396 0.3048)
			(end 0.120396 0.2794)
			(stroke
				(width 0.1)
				(type default)
			)
			(layer "F.Fab")
		)
		(fp_line
			(start 0.12065 -0.3048)
			(end 0.67945 -0.3048)
			(stroke
				(width 0.1)
				(type default)
			)
			(layer "F.Fab")
		)
		(fp_line
			(start 0.12065 -0.2794)
			(end 0.12065 -0.3048)
			(stroke
				(width 0.1)
				(type default)
			)
			(layer "F.Fab")
		)
		(fp_line
			(start 0.67945 -0.3048)
			(end 0.67945 0.3048)
			(stroke
				(width 0.1)
				(type default)
			)
			(layer "F.Fab")
		)
		(fp_line
			(start 0.67945 0.3048)
			(end 0.120396 0.3048)
			(stroke
				(width 0.1)
				(type default)
			)
			(layer "F.Fab")
		)
		(pad "1" smd circle
			(at -0.40005 0)
			(size 0 0)
			(layers "F.Cu" "F.Mask" "F.Paste")
			(net "FM_SMB_2_ALERT_GPU_ISO_R_N")
		)
		(pad "2" smd circle
			(at 0.40005 0)
			(size 0 0)
			(layers "F.Cu" "F.Mask" "F.Paste")
			(net "FM_SMB_2_ALERT_GPU_ISO_N")
		)
	)
	(footprint ""
		(layer "F.Cu")
		(at 117.895624 -258.405376 180)
		(property "Reference" "C2288"
			(at 0 0 180)
			(layer "F.SilkS")
			(hide yes)
			(effects
				(font
					(size 1.27 1.27)
				)
			)
		)
		(property "Value" ""
			(at 0 0 180)
			(layer "F.Fab")
			(effects
				(font
					(size 1.27 1.27)
				)
			)
		)
		(duplicate_pad_numbers_are_jumpers no)
		(fp_line
			(start 0.7874 0.4064)
			(end -0.7874 0.4064)
			(stroke
				(width 0.1524)
				(type default)
			)
			(layer "F.SilkS")
		)
		(fp_line
			(start 0.7874 -0.4064)
			(end 0.7874 0.4064)
			(stroke
				(width 0.1524)
				(type default)
			)
			(layer "F.SilkS")
		)
		(fp_line
			(start -0.7874 0.4064)
			(end -0.7874 -0.4064)
			(stroke
				(width 0.1524)
				(type default)
			)
			(layer "F.SilkS")
		)
		(fp_line
			(start -0.7874 -0.4064)
			(end 0.7874 -0.4064)
			(stroke
				(width 0.1524)
				(type default)
			)
			(layer "F.SilkS")
		)
		(fp_line
			(start 0.67945 0.3048)
			(end 0.120396 0.3048)
			(stroke
				(width 0.1)
				(type default)
			)
			(layer "F.Fab")
		)
		(fp_line
			(start 0.67945 -0.3048)
			(end 0.67945 0.3048)
			(stroke
				(width 0.1)
				(type default)
			)
			(layer "F.Fab")
		)
		(fp_line
			(start 0.12065 -0.2794)
			(end 0.12065 -0.3048)
			(stroke
				(width 0.1)
				(type default)
			)
			(layer "F.Fab")
		)
		(fp_line
			(start 0.12065 -0.3048)
			(end 0.67945 -0.3048)
			(stroke
				(width 0.1)
				(type default)
			)
			(layer "F.Fab")
		)
		(fp_line
			(start 0.120396 0.3048)
			(end 0.120396 0.2794)
			(stroke
				(width 0.1)
				(type default)
			)
			(layer "F.Fab")
		)
		(fp_line
			(start 0.120396 0.2794)
			(end -0.12065 0.2794)
			(stroke
				(width 0.1)
				(type default)
			)
			(layer "F.Fab")
		)
		(fp_line
			(start -0.12065 0.3048)
			(end -0.67945 0.3048)
			(stroke
				(width 0.1)
				(type default)
			)
			(layer "F.Fab")
		)
		(fp_line
			(start -0.12065 0.2794)
			(end -0.12065 0.3048)
			(stroke
				(width 0.1)
				(type default)
			)
			(layer "F.Fab")
		)
		(fp_line
			(start -0.12065 -0.2794)
			(end 0.12065 -0.2794)
			(stroke
				(width 0.1)
				(type default)
			)
			(layer "F.Fab")
		)
		(fp_line
			(start -0.12065 -0.305054)
			(end -0.12065 -0.2794)
			(stroke
				(width 0.1)
				(type default)
			)
			(layer "F.Fab")
		)
		(fp_line
			(start -0.67945 0.3048)
			(end -0.67945 -0.305054)
			(stroke
				(width 0.1)
				(type default)
			)
			(layer "F.Fab")
		)
		(fp_line
			(start -0.67945 -0.305054)
			(end -0.12065 -0.305054)
			(stroke
				(width 0.1)
				(type default)
			)
			(layer "F.Fab")
		)
		(pad "1" smd circle
			(at -0.40005 0 180)
			(size 0 0)
			(layers "F.Cu" "F.Mask" "F.Paste")
			(net "PVDDCR_SOC_P1")
		)
		(pad "2" smd circle
			(at 0.40005 0 180)
			(size 0 0)
			(layers "F.Cu" "F.Mask" "F.Paste")
			(net "GND")
		)
	)
)
